(kicad_pcb
	(version 20260206)
	(generator "pcbnew")
	(generator_version "10.0")
	(general
		(thickness 1.6)
		(legacy_teardrops no)
	)
	(paper "A4")
	(title_block
		(title "panther-plus-userver — 13130-1b_20150205.brd")
		(comment 1 "Honey Badger (Wiwynn) / footprint 406 of 1509 (DIMM2), pads 37-43 of 210")
	)
	(layers
		(0 "F.Cu" signal "TOP")
		(4 "In1.Cu" signal "L2")
		(6 "In2.Cu" signal "L3")
		(8 "In3.Cu" signal "L4")
		(10 "In4.Cu" signal "L5")
		(12 "In5.Cu" signal "L6")
		(14 "In6.Cu" signal "L7")
		(16 "In7.Cu" signal "L8")
		(18 "In8.Cu" signal "L9")
		(20 "In9.Cu" signal "L10")
		(22 "In10.Cu" signal "L11")
		(2 "B.Cu" signal "BOTTOM")
		(9 "F.Adhes" user "F.Adhesive")
		(11 "B.Adhes" user "B.Adhesive")
		(13 "F.Paste" user "Package Geometry/Pastemask Top")
		(15 "B.Paste" user "Package Geometry/Pastemask Bottom")
		(5 "F.SilkS" user "Ref Des/Silkscreen Top")
		(7 "B.SilkS" user "Ref Des/Silkscreen Bottom")
		(1 "F.Mask" user "Board Geometry/Soldermask Top")
		(3 "B.Mask" user "Board Geometry/Soldermask Bottom")
		(17 "Dwgs.User" user "User.Drawings")
		(19 "Cmts.User" user "User.Comments")
		(21 "Eco1.User" user "User.Eco1")
		(23 "Eco2.User" user "User.Eco2")
		(25 "Edge.Cuts" user "Board Geometry/Outline")
		(27 "Margin" user)
		(31 "F.CrtYd" user "Package Geometry/Place Bound Top")
		(29 "B.CrtYd" user "Package Geometry/Place Bound Bottom")
		(35 "F.Fab" user "Ref Des/Assembly Top")
		(33 "B.Fab" user "Ref Des/Assembly Bottom")
	)
	(footprint ""
		(layer "F.Cu")
		(at 158.500064 -66.699892 180)
		(property "Reference" "DIMM2"
			(at 0 0 180)
			(layer "F.SilkS")
			(hide yes)
			(effects
				(font
					(size 1.27 1.27)
				)
			)
		)
		(property "Value" "DDR3-204P-174-COLAY-1-GP"
			(at -40.682164 -17.468088 180)
			(unlocked yes)
			(layer "F.Fab")
			(hide yes)
			(effects
				(font
					(size 1.016 1.016)
					(thickness 0.1524)
				)
			)
		)
		(property "Device Type" "AS0A626-H8SN-7H-COLAY-1"
			(at -40.682164 -18.992088 180)
			(unlocked yes)
			(layer "F.Fab")
			(hide yes)
			(effects
				(font
					(size 1.016 1.016)
					(thickness 0.1524)
				)
			)
		)
		(duplicate_pad_numbers_are_jumpers no)
		(pad "35" smd custom
			(at -21.450046 4.106672 180)
			(size 0.1143 0.1143)
			(layers "F.Cu" "F.Mask" "F.Paste")
			(net "GND")
			(options
				(clearance outline)
				(anchor circle)
			)
			(primitives
				(gr_poly
					(pts
						(xy 0 0.9017) (xy -0.03175 0.89916) (xy -0.0635 0.889) (xy -0.09144 0.87376) (xy -0.11684 0.85344)
						(xy -0.13716 0.82804) (xy -0.1524 0.8001) (xy -0.16256 0.76835) (xy -0.1651 0.7366) (xy -0.1651 0.11938)
						(xy -0.17272 0.11176) (xy -0.19812 0.0762) (xy -0.2032 0.06604) (xy -0.20701 0.05715) (xy -0.21209 0.04699)
						(xy -0.2159 0.03683) (xy -0.21844 0.02667) (xy -0.22225 0.01524) (xy -0.22352 0.00508) (xy -0.22606 -0.00508)
						(xy -0.22733 -0.01651) (xy -0.22733 -0.02667) (xy -0.2286 -0.0381) (xy -0.22733 -0.04953) (xy -0.22733 -0.05969)
						(xy -0.22606 -0.07112) (xy -0.22352 -0.08128) (xy -0.22225 -0.09144) (xy -0.21844 -0.10287) (xy -0.2159 -0.11303)
						(xy -0.21209 -0.12319) (xy -0.20701 -0.13335) (xy -0.2032 -0.14224) (xy -0.19812 -0.1524) (xy -0.17272 -0.18796)
						(xy -0.1651 -0.19558) (xy -0.1651 -0.7366) (xy -0.16256 -0.76835) (xy -0.1524 -0.8001) (xy -0.13716 -0.82804)
						(xy -0.11684 -0.85344) (xy -0.09144 -0.87376) (xy -0.0635 -0.889) (xy -0.03175 -0.89916) (xy 0 -0.9017)
						(xy 0.03175 -0.89916) (xy 0.0635 -0.889) (xy 0.09144 -0.87376) (xy 0.11684 -0.85344) (xy 0.13716 -0.82804)
						(xy 0.1524 -0.8001) (xy 0.16256 -0.76835) (xy 0.1651 -0.7366) (xy 0.1651 -0.19685) (xy 0.17272 -0.18923)
						(xy 0.17907 -0.18034) (xy 0.18669 -0.17145) (xy 0.19177 -0.16256) (xy 0.19812 -0.15367) (xy 0.20828 -0.13335)
						(xy 0.21971 -0.10287) (xy 0.22225 -0.09271) (xy 0.22479 -0.08128) (xy 0.22606 -0.07112) (xy 0.2286 -0.05969)
						(xy 0.2286 -0.01651) (xy 0.22606 -0.00508) (xy 0.22479 0.00508) (xy 0.22225 0.01651) (xy 0.21971 0.02667)
						(xy 0.20828 0.05715) (xy 0.19812 0.07747) (xy 0.19177 0.08636) (xy 0.18669 0.09525) (xy 0.17907 0.10414)
						(xy 0.17272 0.11303) (xy 0.1651 0.12065) (xy 0.1651 0.7366) (xy 0.16256 0.76835) (xy 0.1524 0.8001)
						(xy 0.13716 0.82804) (xy 0.11684 0.85344) (xy 0.09144 0.87376) (xy 0.0635 0.889) (xy 0.03175 0.89916)
					)
					(width 0)
					(fill yes)
				)
			)
		)
		(pad "36" smd custom
			(at -21.150072 -4.106672 180)
			(size 0.1143 0.1143)
			(layers "F.Cu" "F.Mask" "F.Paste")
			(net "M_A_DQ11")
			(options
				(clearance outline)
				(anchor circle)
			)
			(primitives
				(gr_poly
					(pts
						(xy 0 0.9017) (xy -0.03175 0.89916) (xy -0.0635 0.889) (xy -0.09144 0.87376) (xy -0.11684 0.85344)
						(xy -0.13716 0.82804) (xy -0.1524 0.8001) (xy -0.16256 0.76835) (xy -0.1651 0.7366) (xy -0.1651 0.19685)
						(xy -0.17272 0.18923) (xy -0.17907 0.18034) (xy -0.18669 0.17145) (xy -0.19177 0.16256) (xy -0.19812 0.15367)
						(xy -0.20828 0.13335) (xy -0.21971 0.10287) (xy -0.22225 0.09271) (xy -0.22479 0.08128) (xy -0.22606 0.07112)
						(xy -0.2286 0.05969) (xy -0.2286 0.01651) (xy -0.22606 0.00508) (xy -0.22479 -0.00508) (xy -0.22225 -0.01651)
						(xy -0.21971 -0.02667) (xy -0.20828 -0.05715) (xy -0.19812 -0.07747) (xy -0.19177 -0.08636) (xy -0.18669 -0.09525)
						(xy -0.17907 -0.10414) (xy -0.17272 -0.11303) (xy -0.1651 -0.12065) (xy -0.1651 -0.7366) (xy -0.16256 -0.76835)
						(xy -0.1524 -0.8001) (xy -0.13716 -0.82804) (xy -0.11684 -0.85344) (xy -0.09144 -0.87376) (xy -0.0635 -0.889)
						(xy -0.03175 -0.89916) (xy 0 -0.9017) (xy 0.03175 -0.89916) (xy 0.0635 -0.889) (xy 0.09144 -0.87376)
						(xy 0.11684 -0.85344) (xy 0.13716 -0.82804) (xy 0.1524 -0.8001) (xy 0.16256 -0.76835) (xy 0.1651 -0.7366)
						(xy 0.1651 -0.11938) (xy 0.17272 -0.11176) (xy 0.19812 -0.0762) (xy 0.2032 -0.06604) (xy 0.20701 -0.05715)
						(xy 0.21209 -0.04699) (xy 0.2159 -0.03683) (xy 0.21844 -0.02667) (xy 0.22225 -0.01524) (xy 0.22352 -0.00508)
						(xy 0.22606 0.00508) (xy 0.22733 0.01651) (xy 0.22733 0.02667) (xy 0.2286 0.0381) (xy 0.22733 0.04953)
						(xy 0.22733 0.05969) (xy 0.22606 0.07112) (xy 0.22352 0.08128) (xy 0.22225 0.09144) (xy 0.21844 0.10287)
						(xy 0.2159 0.11303) (xy 0.21209 0.12319) (xy 0.20701 0.13335) (xy 0.2032 0.14224) (xy 0.19812 0.1524)
						(xy 0.17272 0.18796) (xy 0.1651 0.19558) (xy 0.1651 0.7366) (xy 0.16256 0.76835) (xy 0.1524 0.8001)
						(xy 0.13716 0.82804) (xy 0.11684 0.85344) (xy 0.09144 0.87376) (xy 0.0635 0.889) (xy 0.03175 0.89916)
					)
					(width 0)
					(fill yes)
				)
			)
		)
		(pad "37" smd custom
			(at -20.850098 4.106672 180)
			(size 0.1143 0.1143)
			(layers "F.Cu" "F.Mask" "F.Paste")
			(net "M_A_DQ20")
			(options
				(clearance outline)
				(anchor circle)
			)
			(primitives
				(gr_poly
					(pts
						(xy 0 0.9017) (xy -0.03175 0.89916) (xy -0.0635 0.889) (xy -0.09144 0.87376) (xy -0.11684 0.85344)
						(xy -0.13716 0.82804) (xy -0.1524 0.8001) (xy -0.16256 0.76835) (xy -0.1651 0.7366) (xy -0.1651 -0.13462)
						(xy -0.17272 -0.14224) (xy -0.19812 -0.1778) (xy -0.2032 -0.18796) (xy -0.20701 -0.19685) (xy -0.21209 -0.20701)
						(xy -0.2159 -0.21717) (xy -0.21844 -0.22733) (xy -0.22225 -0.23876) (xy -0.22352 -0.24892) (xy -0.22606 -0.25908)
						(xy -0.22733 -0.27051) (xy -0.22733 -0.28067) (xy -0.2286 -0.2921) (xy -0.22733 -0.30353) (xy -0.22733 -0.31369)
						(xy -0.22606 -0.32512) (xy -0.22352 -0.33528) (xy -0.22225 -0.34544) (xy -0.21844 -0.35687) (xy -0.2159 -0.36703)
						(xy -0.21209 -0.37719) (xy -0.20701 -0.38735) (xy -0.2032 -0.39624) (xy -0.19812 -0.4064) (xy -0.17272 -0.44196)
						(xy -0.1651 -0.44958) (xy -0.1651 -0.7366) (xy -0.16256 -0.76835) (xy -0.1524 -0.8001) (xy -0.13716 -0.82804)
						(xy -0.11684 -0.85344) (xy -0.09144 -0.87376) (xy -0.0635 -0.889) (xy -0.03175 -0.89916) (xy 0 -0.9017)
						(xy 0.03175 -0.89916) (xy 0.0635 -0.889) (xy 0.09144 -0.87376) (xy 0.11684 -0.85344) (xy 0.13716 -0.82804)
						(xy 0.1524 -0.8001) (xy 0.16256 -0.76835) (xy 0.1651 -0.7366) (xy 0.1651 -0.44958) (xy 0.17272 -0.44196)
						(xy 0.19812 -0.4064) (xy 0.2032 -0.39624) (xy 0.20701 -0.38735) (xy 0.21209 -0.37719) (xy 0.2159 -0.36703)
						(xy 0.21844 -0.35687) (xy 0.22225 -0.34544) (xy 0.22352 -0.33528) (xy 0.22606 -0.32512) (xy 0.22733 -0.31369)
						(xy 0.22733 -0.30353) (xy 0.2286 -0.2921) (xy 0.22733 -0.28067) (xy 0.22733 -0.27051) (xy 0.22606 -0.25908)
						(xy 0.22352 -0.24892) (xy 0.22225 -0.23876) (xy 0.21844 -0.22733) (xy 0.2159 -0.21717) (xy 0.21209 -0.20701)
						(xy 0.20701 -0.19685) (xy 0.2032 -0.18796) (xy 0.19812 -0.1778) (xy 0.17272 -0.14224) (xy 0.1651 -0.13462)
						(xy 0.1651 0.7366) (xy 0.16256 0.76835) (xy 0.1524 0.8001) (xy 0.13716 0.82804) (xy 0.11684 0.85344)
						(xy 0.09144 0.87376) (xy 0.0635 0.889) (xy 0.03175 0.89916)
					)
					(width 0)
					(fill yes)
				)
			)
		)
		(pad "38" smd custom
			(at -20.550124 -4.106672 180)
			(size 0.1143 0.1143)
			(layers "F.Cu" "F.Mask" "F.Paste")
			(net "GND")
			(options
				(clearance outline)
				(anchor circle)
			)
			(primitives
				(gr_poly
					(pts
						(xy 0 0.9017) (xy -0.03175 0.89916) (xy -0.0635 0.889) (xy -0.09144 0.87376) (xy -0.11684 0.85344)
						(xy -0.13716 0.82804) (xy -0.1524 0.8001) (xy -0.16256 0.76835) (xy -0.1651 0.7366) (xy -0.1651 0.44958)
						(xy -0.17272 0.44196) (xy -0.19812 0.4064) (xy -0.2032 0.39624) (xy -0.20701 0.38735) (xy -0.21209 0.37719)
						(xy -0.2159 0.36703) (xy -0.21844 0.35687) (xy -0.22225 0.34544) (xy -0.22352 0.33528) (xy -0.22606 0.32512)
						(xy -0.22733 0.31369) (xy -0.22733 0.30353) (xy -0.2286 0.2921) (xy -0.22733 0.28067) (xy -0.22733 0.27051)
						(xy -0.22606 0.25908) (xy -0.22352 0.24892) (xy -0.22225 0.23876) (xy -0.21844 0.22733) (xy -0.2159 0.21717)
						(xy -0.21209 0.20701) (xy -0.20701 0.19685) (xy -0.2032 0.18796) (xy -0.19812 0.1778) (xy -0.17272 0.14224)
						(xy -0.1651 0.13462) (xy -0.1651 -0.7366) (xy -0.16256 -0.76835) (xy -0.1524 -0.8001) (xy -0.13716 -0.82804)
						(xy -0.11684 -0.85344) (xy -0.09144 -0.87376) (xy -0.0635 -0.889) (xy -0.03175 -0.89916) (xy 0 -0.9017)
						(xy 0.03175 -0.89916) (xy 0.0635 -0.889) (xy 0.09144 -0.87376) (xy 0.11684 -0.85344) (xy 0.13716 -0.82804)
						(xy 0.1524 -0.8001) (xy 0.16256 -0.76835) (xy 0.1651 -0.7366) (xy 0.1651 0.13462) (xy 0.17272 0.14224)
						(xy 0.19812 0.1778) (xy 0.2032 0.18796) (xy 0.20701 0.19685) (xy 0.21209 0.20701) (xy 0.2159 0.21717)
						(xy 0.21844 0.22733) (xy 0.22225 0.23876) (xy 0.22352 0.24892) (xy 0.22606 0.25908) (xy 0.22733 0.27051)
						(xy 0.22733 0.28067) (xy 0.2286 0.2921) (xy 0.22733 0.30353) (xy 0.22733 0.31369) (xy 0.22606 0.32512)
						(xy 0.22352 0.33528) (xy 0.22225 0.34544) (xy 0.21844 0.35687) (xy 0.2159 0.36703) (xy 0.21209 0.37719)
						(xy 0.20701 0.38735) (xy 0.2032 0.39624) (xy 0.19812 0.4064) (xy 0.17272 0.44196) (xy 0.1651 0.44958)
						(xy 0.1651 0.7366) (xy 0.16256 0.76835) (xy 0.1524 0.8001) (xy 0.13716 0.82804) (xy 0.11684 0.85344)
						(xy 0.09144 0.87376) (xy 0.0635 0.889) (xy 0.03175 0.89916)
					)
					(width 0)
					(fill yes)
				)
			)
		)
		(pad "39" smd custom
			(at -20.249896 4.106672 180)
			(size 0.1143 0.1143)
			(layers "F.Cu" "F.Mask" "F.Paste")
			(net "M_A_DQ21")
			(options
				(clearance outline)
				(anchor circle)
			)
			(primitives
				(gr_poly
					(pts
						(xy 0 0.9017) (xy -0.03175 0.89916) (xy -0.0635 0.889) (xy -0.09144 0.87376) (xy -0.11684 0.85344)
						(xy -0.13716 0.82804) (xy -0.1524 0.8001) (xy -0.16256 0.76835) (xy -0.1651 0.7366) (xy -0.1651 0.11938)
						(xy -0.17272 0.11176) (xy -0.19812 0.0762) (xy -0.2032 0.06604) (xy -0.20701 0.05715) (xy -0.21209 0.04699)
						(xy -0.2159 0.03683) (xy -0.21844 0.02667) (xy -0.22225 0.01524) (xy -0.22352 0.00508) (xy -0.22606 -0.00508)
						(xy -0.22733 -0.01651) (xy -0.22733 -0.02667) (xy -0.2286 -0.0381) (xy -0.22733 -0.04953) (xy -0.22733 -0.05969)
						(xy -0.22606 -0.07112) (xy -0.22352 -0.08128) (xy -0.22225 -0.09144) (xy -0.21844 -0.10287) (xy -0.2159 -0.11303)
						(xy -0.21209 -0.12319) (xy -0.20701 -0.13335) (xy -0.2032 -0.14224) (xy -0.19812 -0.1524) (xy -0.17272 -0.18796)
						(xy -0.1651 -0.19558) (xy -0.1651 -0.7366) (xy -0.16256 -0.76835) (xy -0.1524 -0.8001) (xy -0.13716 -0.82804)
						(xy -0.11684 -0.85344) (xy -0.09144 -0.87376) (xy -0.0635 -0.889) (xy -0.03175 -0.89916) (xy 0 -0.9017)
						(xy 0.03175 -0.89916) (xy 0.0635 -0.889) (xy 0.09144 -0.87376) (xy 0.11684 -0.85344) (xy 0.13716 -0.82804)
						(xy 0.1524 -0.8001) (xy 0.16256 -0.76835) (xy 0.1651 -0.7366) (xy 0.1651 -0.19685) (xy 0.17272 -0.18923)
						(xy 0.17907 -0.18034) (xy 0.18669 -0.17145) (xy 0.19177 -0.16256) (xy 0.19812 -0.15367) (xy 0.20828 -0.13335)
						(xy 0.21971 -0.10287) (xy 0.22225 -0.09271) (xy 0.22479 -0.08128) (xy 0.22606 -0.07112) (xy 0.2286 -0.05969)
						(xy 0.2286 -0.01651) (xy 0.22606 -0.00508) (xy 0.22479 0.00508) (xy 0.22225 0.01651) (xy 0.21971 0.02667)
						(xy 0.20828 0.05715) (xy 0.19812 0.07747) (xy 0.19177 0.08636) (xy 0.18669 0.09525) (xy 0.17907 0.10414)
						(xy 0.17272 0.11303) (xy 0.1651 0.12065) (xy 0.1651 0.7366) (xy 0.16256 0.76835) (xy 0.1524 0.8001)
						(xy 0.13716 0.82804) (xy 0.11684 0.85344) (xy 0.09144 0.87376) (xy 0.0635 0.889) (xy 0.03175 0.89916)
					)
					(width 0)
					(fill yes)
				)
			)
		)
		(pad "40" smd custom
			(at -19.949922 -4.106672 180)
			(size 0.1143 0.1143)
			(layers "F.Cu" "F.Mask" "F.Paste")
			(net "M_A_DQ16")
			(options
				(clearance outline)
				(anchor circle)
			)
			(primitives
				(gr_poly
					(pts
						(xy 0 0.9017) (xy -0.03175 0.89916) (xy -0.0635 0.889) (xy -0.09144 0.87376) (xy -0.11684 0.85344)
						(xy -0.13716 0.82804) (xy -0.1524 0.8001) (xy -0.16256 0.76835) (xy -0.1651 0.7366) (xy -0.1651 0.19685)
						(xy -0.17272 0.18923) (xy -0.17907 0.18034) (xy -0.18669 0.17145) (xy -0.19177 0.16256) (xy -0.19812 0.15367)
						(xy -0.20828 0.13335) (xy -0.21971 0.10287) (xy -0.22225 0.09271) (xy -0.22479 0.08128) (xy -0.22606 0.07112)
						(xy -0.2286 0.05969) (xy -0.2286 0.01651) (xy -0.22606 0.00508) (xy -0.22479 -0.00508) (xy -0.22225 -0.01651)
						(xy -0.21971 -0.02667) (xy -0.20828 -0.05715) (xy -0.19812 -0.07747) (xy -0.19177 -0.08636) (xy -0.18669 -0.09525)
						(xy -0.17907 -0.10414) (xy -0.17272 -0.11303) (xy -0.1651 -0.12065) (xy -0.1651 -0.7366) (xy -0.16256 -0.76835)
						(xy -0.1524 -0.8001) (xy -0.13716 -0.82804) (xy -0.11684 -0.85344) (xy -0.09144 -0.87376) (xy -0.0635 -0.889)
						(xy -0.03175 -0.89916) (xy 0 -0.9017) (xy 0.03175 -0.89916) (xy 0.0635 -0.889) (xy 0.09144 -0.87376)
						(xy 0.11684 -0.85344) (xy 0.13716 -0.82804) (xy 0.1524 -0.8001) (xy 0.16256 -0.76835) (xy 0.1651 -0.7366)
						(xy 0.1651 -0.11938) (xy 0.17272 -0.11176) (xy 0.19812 -0.0762) (xy 0.2032 -0.06604) (xy 0.20701 -0.05715)
						(xy 0.21209 -0.04699) (xy 0.2159 -0.03683) (xy 0.21844 -0.02667) (xy 0.22225 -0.01524) (xy 0.22352 -0.00508)
						(xy 0.22606 0.00508) (xy 0.22733 0.01651) (xy 0.22733 0.02667) (xy 0.2286 0.0381) (xy 0.22733 0.04953)
						(xy 0.22733 0.05969) (xy 0.22606 0.07112) (xy 0.22352 0.08128) (xy 0.22225 0.09144) (xy 0.21844 0.10287)
						(xy 0.2159 0.11303) (xy 0.21209 0.12319) (xy 0.20701 0.13335) (xy 0.2032 0.14224) (xy 0.19812 0.1524)
						(xy 0.17272 0.18796) (xy 0.1651 0.19558) (xy 0.1651 0.7366) (xy 0.16256 0.76835) (xy 0.1524 0.8001)
						(xy 0.13716 0.82804) (xy 0.11684 0.85344) (xy 0.09144 0.87376) (xy 0.0635 0.889) (xy 0.03175 0.89916)
					)
					(width 0)
					(fill yes)
				)
			)
		)
		(pad "41" smd custom
			(at -19.649948 4.106672 180)
			(size 0.1143 0.1143)
			(layers "F.Cu" "F.Mask" "F.Paste")
			(net "GND")
			(options
				(clearance outline)
				(anchor circle)
			)
			(primitives
				(gr_poly
					(pts
						(xy 0 0.9017) (xy -0.03175 0.89916) (xy -0.0635 0.889) (xy -0.09144 0.87376) (xy -0.11684 0.85344)
						(xy -0.13716 0.82804) (xy -0.1524 0.8001) (xy -0.16256 0.76835) (xy -0.1651 0.7366) (xy -0.1651 -0.13462)
						(xy -0.17272 -0.14224) (xy -0.19812 -0.1778) (xy -0.2032 -0.18796) (xy -0.20701 -0.19685) (xy -0.21209 -0.20701)
						(xy -0.2159 -0.21717) (xy -0.21844 -0.22733) (xy -0.22225 -0.23876) (xy -0.22352 -0.24892) (xy -0.22606 -0.25908)
						(xy -0.22733 -0.27051) (xy -0.22733 -0.28067) (xy -0.2286 -0.2921) (xy -0.22733 -0.30353) (xy -0.22733 -0.31369)
						(xy -0.22606 -0.32512) (xy -0.22352 -0.33528) (xy -0.22225 -0.34544) (xy -0.21844 -0.35687) (xy -0.2159 -0.36703)
						(xy -0.21209 -0.37719) (xy -0.20701 -0.38735) (xy -0.2032 -0.39624) (xy -0.19812 -0.4064) (xy -0.17272 -0.44196)
						(xy -0.1651 -0.44958) (xy -0.1651 -0.7366) (xy -0.16256 -0.76835) (xy -0.1524 -0.8001) (xy -0.13716 -0.82804)
						(xy -0.11684 -0.85344) (xy -0.09144 -0.87376) (xy -0.0635 -0.889) (xy -0.03175 -0.89916) (xy 0 -0.9017)
						(xy 0.03175 -0.89916) (xy 0.0635 -0.889) (xy 0.09144 -0.87376) (xy 0.11684 -0.85344) (xy 0.13716 -0.82804)
						(xy 0.1524 -0.8001) (xy 0.16256 -0.76835) (xy 0.1651 -0.7366) (xy 0.1651 -0.44958) (xy 0.17272 -0.44196)
						(xy 0.19812 -0.4064) (xy 0.2032 -0.39624) (xy 0.20701 -0.38735) (xy 0.21209 -0.37719) (xy 0.2159 -0.36703)
						(xy 0.21844 -0.35687) (xy 0.22225 -0.34544) (xy 0.22352 -0.33528) (xy 0.22606 -0.32512) (xy 0.22733 -0.31369)
						(xy 0.22733 -0.30353) (xy 0.2286 -0.2921) (xy 0.22733 -0.28067) (xy 0.22733 -0.27051) (xy 0.22606 -0.25908)
						(xy 0.22352 -0.24892) (xy 0.22225 -0.23876) (xy 0.21844 -0.22733) (xy 0.2159 -0.21717) (xy 0.21209 -0.20701)
						(xy 0.20701 -0.19685) (xy 0.2032 -0.18796) (xy 0.19812 -0.1778) (xy 0.17272 -0.14224) (xy 0.1651 -0.13462)
						(xy 0.1651 0.7366) (xy 0.16256 0.76835) (xy 0.1524 0.8001) (xy 0.13716 0.82804) (xy 0.11684 0.85344)
						(xy 0.09144 0.87376) (xy 0.0635 0.889) (xy 0.03175 0.89916)
					)
					(width 0)
					(fill yes)
				)
			)
		)
	)
)
